(kicad_pcb
	(version 20260206)
	(generator "pcbnew")
	(generator_version "10.0")
	(general
		(thickness 1.6)
		(legacy_teardrops no)
	)
	(paper "A4")
	(title_block
		(title "v1-chassis-manager — T6M_CM_d_v01_1031_1645.brd")
		(comment 1 "Open CloudServer (Microsoft) / footprints 1192-1200 of 2512")
	)
	(layers
		(0 "F.Cu" signal "TOP")
		(4 "In1.Cu" signal "GND1")
		(6 "In2.Cu" signal "IN1")
		(8 "In3.Cu" signal "VCC1")
		(10 "In4.Cu" signal "VCC2")
		(12 "In5.Cu" signal "GND2")
		(14 "In6.Cu" signal "IN2")
		(16 "In7.Cu" signal "IN3")
		(18 "In8.Cu" signal "GND3")
		(2 "B.Cu" signal "BOTTOM")
		(9 "F.Adhes" user "F.Adhesive")
		(11 "B.Adhes" user "B.Adhesive")
		(13 "F.Paste" user "Package Geometry/Pastemask Top")
		(15 "B.Paste" user "Package Geometry/Pastemask Bottom")
		(5 "F.SilkS" user "Ref Des/Silkscreen Top")
		(7 "B.SilkS" user "Ref Des/Silkscreen Bottom")
		(1 "F.Mask" user "Board Geometry/Soldermask Top")
		(3 "B.Mask" user "Board Geometry/Soldermask Bottom")
		(17 "Dwgs.User" user "User.Drawings")
		(19 "Cmts.User" user "User.Comments")
		(21 "Eco1.User" user "User.Eco1")
		(23 "Eco2.User" user "User.Eco2")
		(25 "Edge.Cuts" user "Board Geometry/Outline")
		(27 "Margin" user)
		(31 "F.CrtYd" user "Package Geometry/Place Bound Top")
		(29 "B.CrtYd" user "Package Geometry/Place Bound Bottom")
		(35 "F.Fab" user "Ref Des/Assembly Top")
		(33 "B.Fab" user "Ref Des/Assembly Bottom")
	)
	(footprint ""
		(layer "F.Cu")
		(at 118.17477 -123.296934 90)
		(property "Reference" "PC91"
			(at -0.529844 3.730752 90)
			(unlocked yes)
			(layer "F.SilkS")
			(effects
				(font
					(size 0.7874 0.5842)
					(thickness 0.1524)
				)
				(justify left)
			)
		)
		(property "Value" ""
			(at 0 0 90)
			(layer "F.Fab")
			(effects
				(font
					(size 1.27 1.27)
				)
			)
		)
		(duplicate_pad_numbers_are_jumpers no)
		(fp_line
			(start 2.2098 -0.9398)
			(end 2.2098 0.9398)
			(stroke
				(width 0.1524)
				(type default)
			)
			(layer "F.SilkS")
		)
		(fp_line
			(start 0 -0.9398)
			(end 0 0.9398)
			(stroke
				(width 0.1524)
				(type default)
			)
			(layer "F.SilkS")
		)
		(fp_line
			(start -2.2098 -0.9398)
			(end 2.2098 -0.9398)
			(stroke
				(width 0.1524)
				(type default)
			)
			(layer "F.SilkS")
		)
		(fp_line
			(start 2.2098 0.9398)
			(end -2.2098 0.9398)
			(stroke
				(width 0.1524)
				(type default)
			)
			(layer "F.SilkS")
		)
		(fp_line
			(start -2.2098 0.9398)
			(end -2.2098 -0.9398)
			(stroke
				(width 0.1524)
				(type default)
			)
			(layer "F.SilkS")
		)
		(fp_poly
			(pts
				(xy -1.6764 0.889) (xy -1.6764 0.7874) (xy -2.0574 0.7874) (xy -2.0574 -0.7874) (xy -1.6764 -0.7874)
				(xy -1.6764 -0.9398) (xy 1.6764 -0.9398) (xy 1.6764 -0.7874) (xy 2.0574 -0.7874) (xy 2.0574 0.7874)
				(xy 1.6764 0.7874) (xy 1.6764 0.9398) (xy -1.6764 0.9398)
			)
			(stroke
				(width 0)
				(type default)
			)
			(fill no)
			(layer "F.CrtYd")
		)
		(fp_line
			(start 1.700022 -0.899922)
			(end 1.700022 0.899922)
			(stroke
				(width 0.1)
				(type default)
			)
			(layer "F.Fab")
		)
		(fp_line
			(start -1.700022 -0.899922)
			(end 1.700022 -0.899922)
			(stroke
				(width 0.1)
				(type default)
			)
			(layer "F.Fab")
		)
		(fp_line
			(start 1.700022 0.899922)
			(end -1.700022 0.899922)
			(stroke
				(width 0.1)
				(type default)
			)
			(layer "F.Fab")
		)
		(fp_line
			(start -1.700022 0.899922)
			(end -1.700022 -0.899922)
			(stroke
				(width 0.1)
				(type default)
			)
			(layer "F.Fab")
		)
		(pad "1" smd rect
			(at 1.4732 0 90)
			(size 1.1684 1.5748)
			(layers "F.Cu" "F.Mask" "F.Paste")
			(net "SW_VR_PVCCP_NODE1_VIN_FLT")
		)
		(pad "2" smd rect
			(at -1.4732 0 90)
			(size 1.1684 1.5748)
			(layers "F.Cu" "F.Mask" "F.Paste")
			(net "GND")
		)
	)
	(footprint ""
		(layer "F.Cu")
		(at 82.7278 -83.641184 90)
		(property "Reference" "C24"
			(at -18.13306 1.853184 90)
			(unlocked yes)
			(layer "F.SilkS")
			(effects
				(font
					(size 0.7874 0.5842)
					(thickness 0.1524)
				)
				(justify left)
			)
		)
		(property "Value" ""
			(at 0 0 90)
			(layer "F.Fab")
			(effects
				(font
					(size 1.27 1.27)
				)
			)
		)
		(duplicate_pad_numbers_are_jumpers no)
		(fp_line
			(start 0.7874 -0.4064)
			(end 0.7874 0.4064)
			(stroke
				(width 0.1524)
				(type default)
			)
			(layer "F.SilkS")
		)
		(fp_line
			(start -0.7874 -0.4064)
			(end 0.7874 -0.4064)
			(stroke
				(width 0.1524)
				(type default)
			)
			(layer "F.SilkS")
		)
		(fp_line
			(start 0 0.381)
			(end 0 -0.381)
			(stroke
				(width 0.1524)
				(type default)
			)
			(layer "F.SilkS")
		)
		(fp_line
			(start 0.7874 0.4064)
			(end -0.7874 0.4064)
			(stroke
				(width 0.1524)
				(type default)
			)
			(layer "F.SilkS")
		)
		(fp_line
			(start -0.7874 0.4064)
			(end -0.7874 -0.4064)
			(stroke
				(width 0.1524)
				(type default)
			)
			(layer "F.SilkS")
		)
		(fp_poly
			(pts
				(xy -0.5334 0.254) (xy -0.635 0.254) (xy -0.635 0.2286) (xy -0.635 -0.254) (xy -0.5334 -0.254) (xy -0.5334 -0.2794)
				(xy 0.5334 -0.2794) (xy 0.5334 -0.254) (xy 0.635 -0.254) (xy 0.635 0.254) (xy 0.5334 0.254) (xy 0.5334 0.2794)
				(xy -0.508 0.2794) (xy -0.5334 0.2794)
			)
			(stroke
				(width 0)
				(type default)
			)
			(fill no)
			(layer "F.CrtYd")
		)
		(pad "1" smd rect
			(at 0.40005 0 90)
			(size 0.4572 0.508)
			(layers "F.Cu" "F.Mask" "F.Paste")
			(net "XTAL_CPU_NODE1_X1PAD")
		)
		(pad "2" smd rect
			(at -0.40005 0 90)
			(size 0.4572 0.508)
			(layers "F.Cu" "F.Mask" "F.Paste")
			(net "GND")
		)
	)
	(footprint ""
		(layer "F.Cu")
		(at 186.182 -125.984)
		(property "Reference" "R1272"
			(at 4.064 19.83867 0)
			(unlocked yes)
			(layer "F.SilkS")
			(effects
				(font
					(size 0.7874 0.5842)
					(thickness 0.1524)
				)
				(justify left)
			)
		)
		(property "Value" ""
			(at 0 0 0)
			(layer "F.Fab")
			(effects
				(font
					(size 1.27 1.27)
				)
			)
		)
		(duplicate_pad_numbers_are_jumpers no)
		(fp_line
			(start -0.7874 -0.4064)
			(end 0.7874 -0.4064)
			(stroke
				(width 0.1524)
				(type default)
			)
			(layer "F.SilkS")
		)
		(fp_line
			(start -0.7874 0.4064)
			(end -0.7874 -0.4064)
			(stroke
				(width 0.1524)
				(type default)
			)
			(layer "F.SilkS")
		)
		(fp_line
			(start 0.7874 -0.4064)
			(end 0.7874 0.4064)
			(stroke
				(width 0.1524)
				(type default)
			)
			(layer "F.SilkS")
		)
		(fp_line
			(start 0.7874 0.4064)
			(end -0.7874 0.4064)
			(stroke
				(width 0.1524)
				(type default)
			)
			(layer "F.SilkS")
		)
		(fp_poly
			(pts
				(xy -0.508 0.2794) (xy -0.508 0.2286) (xy -0.635 0.2286) (xy -0.635 -0.254) (xy -0.5334 -0.254)
				(xy -0.5334 -0.2794) (xy 0.5334 -0.2794) (xy 0.5334 -0.254) (xy 0.635 -0.254) (xy 0.635 0.254) (xy 0.5334 0.254)
				(xy 0.5334 0.2794)
			)
			(stroke
				(width 0)
				(type default)
			)
			(fill no)
			(layer "F.CrtYd")
		)
		(pad "1" smd rect
			(at 0.40005 0)
			(size 0.4572 0.508)
			(layers "F.Cu" "F.Mask" "F.Paste")
			(net "SIO_JTAG_CPLD1_TMS")
		)
		(pad "2" smd rect
			(at -0.40005 0)
			(size 0.4572 0.508)
			(layers "F.Cu" "F.Mask" "F.Paste")
			(net "JTAG_CPLD1_TMS")
		)
	)
	(footprint ""
		(layer "F.Cu")
		(at 62.291214 -149.137624 180)
		(property "Reference" "C263"
			(at 30.37205 7.322058 0)
			(unlocked yes)
			(layer "F.SilkS")
			(effects
				(font
					(size 0.7874 0.5842)
					(thickness 0.1524)
				)
				(justify left)
			)
		)
		(property "Value" ""
			(at 0 0 180)
			(layer "F.Fab")
			(effects
				(font
					(size 1.27 1.27)
				)
			)
		)
		(duplicate_pad_numbers_are_jumpers no)
		(fp_line
			(start 0.7874 0.4064)
			(end -0.7874 0.4064)
			(stroke
				(width 0.1524)
				(type default)
			)
			(layer "F.SilkS")
		)
		(fp_line
			(start 0.7874 -0.4064)
			(end 0.7874 0.4064)
			(stroke
				(width 0.1524)
				(type default)
			)
			(layer "F.SilkS")
		)
		(fp_line
			(start 0 0.381)
			(end 0 -0.381)
			(stroke
				(width 0.1524)
				(type default)
			)
			(layer "F.SilkS")
		)
		(fp_line
			(start -0.7874 0.4064)
			(end -0.7874 -0.4064)
			(stroke
				(width 0.1524)
				(type default)
			)
			(layer "F.SilkS")
		)
		(fp_line
			(start -0.7874 -0.4064)
			(end 0.7874 -0.4064)
			(stroke
				(width 0.1524)
				(type default)
			)
			(layer "F.SilkS")
		)
		(fp_poly
			(pts
				(xy -0.5334 0.254) (xy -0.635 0.254) (xy -0.635 0.2286) (xy -0.635 -0.254) (xy -0.5334 -0.254) (xy -0.5334 -0.2794)
				(xy 0.5334 -0.2794) (xy 0.5334 -0.254) (xy 0.635 -0.254) (xy 0.635 0.254) (xy 0.5334 0.254) (xy 0.5334 0.2794)
				(xy -0.508 0.2794) (xy -0.5334 0.2794)
			)
			(stroke
				(width 0)
				(type default)
			)
			(fill no)
			(layer "F.CrtYd")
		)
		(pad "1" smd rect
			(at 0.40005 0 180)
			(size 0.4572 0.508)
			(layers "F.Cu" "F.Mask" "F.Paste")
			(net "BMC_NODE1_DACAV33")
		)
		(pad "2" smd rect
			(at -0.40005 0 180)
			(size 0.4572 0.508)
			(layers "F.Cu" "F.Mask" "F.Paste")
			(net "GND")
		)
	)
	(footprint ""
		(layer "F.Cu")
		(at 90.063066 -100.491544)
		(property "Reference" "U4"
			(at 5.493766 -3.376422 0)
			(unlocked yes)
			(layer "F.SilkS")
			(effects
				(font
					(size 0.7874 0.5842)
					(thickness 0.1524)
				)
				(justify left)
			)
		)
		(property "Value" ""
			(at 0 0 0)
			(layer "F.Fab")
			(effects
				(font
					(size 1.27 1.27)
				)
			)
		)
		(duplicate_pad_numbers_are_jumpers no)
		(fp_line
			(start -2.690114 -2.599944)
			(end 2.690114 -2.599944)
			(stroke
				(width 0.1524)
				(type default)
			)
			(layer "F.SilkS")
		)
		(fp_line
			(start -2.690114 -0.40005)
			(end -2.690114 -2.599944)
			(stroke
				(width 0.1524)
				(type default)
			)
			(layer "F.SilkS")
		)
		(fp_line
			(start -2.690114 0.40005)
			(end -1.905 0)
			(stroke
				(width 0.1524)
				(type default)
			)
			(layer "F.SilkS")
		)
		(fp_line
			(start -2.690114 2.599944)
			(end -2.690114 0.40005)
			(stroke
				(width 0.1524)
				(type default)
			)
			(layer "F.SilkS")
		)
		(fp_line
			(start -1.905 0)
			(end -2.690114 -0.40005)
			(stroke
				(width 0.1524)
				(type default)
			)
			(layer "F.SilkS")
		)
		(fp_line
			(start 2.690114 -2.599944)
			(end 2.690114 2.599944)
			(stroke
				(width 0.1524)
				(type default)
			)
			(layer "F.SilkS")
		)
		(fp_line
			(start 2.690114 2.599944)
			(end -2.690114 2.599944)
			(stroke
				(width 0.1524)
				(type default)
			)
			(layer "F.SilkS")
		)
		(fp_circle
			(center -1.9304 2.0066)
			(end -1.6764 2.0066)
			(stroke
				(width 0.1524)
				(type default)
			)
			(fill no)
			(layer "F.SilkS")
		)
		(fp_poly
			(pts
				(xy -2.1844 4.4958) (xy -2.1844 2.5908) (xy -2.6924 2.5908) (xy -2.6924 -2.5908) (xy -2.1844 -2.5908)
				(xy -2.1844 -4.4958) (xy 2.1844 -4.4958) (xy 2.1844 -2.5908) (xy 2.667 -2.5908) (xy 2.667 2.5908)
				(xy 2.1844 2.5908) (xy 2.1844 4.4958)
			)
			(stroke
				(width 0)
				(type default)
			)
			(fill no)
			(layer "F.CrtYd")
		)
		(pad "1" smd rect
			(at -1.905 3.636518)
			(size 0.5588 1.7272)
			(layers "F.Cu" "F.Mask" "F.Paste")
			(net "SPI_CPU_NODE1_CS0_L")
		)
		(pad "2" smd rect
			(at -0.635 3.636518)
			(size 0.5588 1.7272)
			(layers "F.Cu" "F.Mask" "F.Paste")
			(net "SPI_CPU_NODE1_MISO_R")
		)
		(pad "3" smd rect
			(at 0.635 3.636518)
			(size 0.5588 1.7272)
			(layers "F.Cu" "F.Mask" "F.Paste")
			(net "SPI_CPU_NODE1_WP_L")
		)
		(pad "4" smd rect
			(at 1.905 3.636518)
			(size 0.5588 1.7272)
			(layers "F.Cu" "F.Mask" "F.Paste")
			(net "GND")
		)
		(pad "5" smd rect
			(at 1.905 -3.636518)
			(size 0.5588 1.7272)
			(layers "F.Cu" "F.Mask" "F.Paste")
			(net "SPI_CPU_NODE1_MOSI")
		)
		(pad "6" smd rect
			(at 0.635 -3.636518)
			(size 0.5588 1.7272)
			(layers "F.Cu" "F.Mask" "F.Paste")
			(net "SPI_CPU_NODE1_SCLK")
		)
		(pad "7" smd rect
			(at -0.635 -3.636518)
			(size 0.5588 1.7272)
			(layers "F.Cu" "F.Mask" "F.Paste")
			(net "SPI_CPU_NODE1_HOLD_L")
		)
		(pad "8" smd rect
			(at -1.905 -3.636518)
			(size 0.5588 1.7272)
			(layers "F.Cu" "F.Mask" "F.Paste")
			(net "P3V3_NODE1")
		)
	)
	(footprint ""
		(layer "F.Cu")
		(at 144.916652 -138.53795)
		(property "Reference" "R288"
			(at -0.990346 17.192244 0)
			(unlocked yes)
			(layer "F.SilkS")
			(effects
				(font
					(size 0.7874 0.5842)
					(thickness 0.1524)
				)
				(justify left)
			)
		)
		(property "Value" ""
			(at 0 0 0)
			(layer "F.Fab")
			(effects
				(font
					(size 1.27 1.27)
				)
			)
		)
		(duplicate_pad_numbers_are_jumpers no)
		(fp_line
			(start -0.7874 -0.4064)
			(end 0.7874 -0.4064)
			(stroke
				(width 0.1524)
				(type default)
			)
			(layer "F.SilkS")
		)
		(fp_line
			(start -0.7874 0.4064)
			(end -0.7874 -0.4064)
			(stroke
				(width 0.1524)
				(type default)
			)
			(layer "F.SilkS")
		)
		(fp_line
			(start 0.7874 -0.4064)
			(end 0.7874 0.4064)
			(stroke
				(width 0.1524)
				(type default)
			)
			(layer "F.SilkS")
		)
		(fp_line
			(start 0.7874 0.4064)
			(end -0.7874 0.4064)
			(stroke
				(width 0.1524)
				(type default)
			)
			(layer "F.SilkS")
		)
		(fp_poly
			(pts
				(xy -0.508 0.2794) (xy -0.508 0.2286) (xy -0.635 0.2286) (xy -0.635 -0.254) (xy -0.5334 -0.254)
				(xy -0.5334 -0.2794) (xy 0.5334 -0.2794) (xy 0.5334 -0.254) (xy 0.635 -0.254) (xy 0.635 0.254) (xy 0.5334 0.254)
				(xy 0.5334 0.2794)
			)
			(stroke
				(width 0)
				(type default)
			)
			(fill no)
			(layer "F.CrtYd")
		)
		(pad "1" smd rect
			(at 0.40005 0)
			(size 0.4572 0.508)
			(layers "F.Cu" "F.Mask" "F.Paste")
			(net "GND")
		)
		(pad "2" smd rect
			(at -0.40005 0)
			(size 0.4572 0.508)
			(layers "F.Cu" "F.Mask" "F.Paste")
			(net "PCIE_SW_TEST5")
		)
	)
	(footprint ""
		(layer "F.Cu")
		(at 114.574828 -66.621914)
		(property "Reference" "C197"
			(at 3.47599 -0.185674 0)
			(unlocked yes)
			(layer "F.SilkS")
			(effects
				(font
					(size 0.7874 0.5842)
					(thickness 0.1524)
				)
			)
		)
		(property "Value" ""
			(at 0 0 0)
			(layer "F.Fab")
			(effects
				(font
					(size 1.27 1.27)
				)
			)
		)
		(duplicate_pad_numbers_are_jumpers no)
		(fp_line
			(start -1.2954 -0.5842)
			(end 1.2954 -0.5842)
			(stroke
				(width 0.1524)
				(type default)
			)
			(layer "F.SilkS")
		)
		(fp_line
			(start -1.2954 0.5842)
			(end -1.2954 -0.5842)
			(stroke
				(width 0.1524)
				(type default)
			)
			(layer "F.SilkS")
		)
		(fp_line
			(start 0 -0.5842)
			(end 0 0.5842)
			(stroke
				(width 0.1524)
				(type default)
			)
			(layer "F.SilkS")
		)
		(fp_line
			(start 1.2954 -0.5842)
			(end 1.2954 0.5842)
			(stroke
				(width 0.1524)
				(type default)
			)
			(layer "F.SilkS")
		)
		(fp_line
			(start 1.2954 0.5842)
			(end -1.2954 0.5842)
			(stroke
				(width 0.1524)
				(type default)
			)
			(layer "F.SilkS")
		)
		(fp_poly
			(pts
				(xy 0.8636 -0.4572) (xy 0.8636 -0.3556) (xy 1.143 -0.3556) (xy 1.143 0.3556) (xy 0.8636 0.3556)
				(xy 0.8636 0.4572) (xy -0.8636 0.4572) (xy -0.8636 0.3556) (xy -1.143 0.3556) (xy -1.143 -0.3556)
				(xy -0.8636 -0.3556) (xy -0.8636 -0.4572)
			)
			(stroke
				(width 0)
				(type default)
			)
			(fill no)
			(layer "F.CrtYd")
		)
		(fp_line
			(start -0.884936 -0.504952)
			(end 0.884936 -0.504952)
			(stroke
				(width 0.1)
				(type default)
			)
			(layer "F.Fab")
		)
		(fp_line
			(start -0.884936 0.504952)
			(end -0.884936 -0.504952)
			(stroke
				(width 0.1)
				(type default)
			)
			(layer "F.Fab")
		)
		(fp_line
			(start 0.884936 -0.504952)
			(end 0.884936 0.504952)
			(stroke
				(width 0.1)
				(type default)
			)
			(layer "F.Fab")
		)
		(fp_line
			(start 0.884936 0.504952)
			(end -0.884936 0.504952)
			(stroke
				(width 0.1)
				(type default)
			)
			(layer "F.Fab")
		)
		(pad "1" smd rect
			(at 0.7366 0 90)
			(size 0.7112 0.8128)
			(layers "F.Cu" "F.Mask" "F.Paste")
			(net "GND")
		)
		(pad "2" smd rect
			(at -0.7366 0 90)
			(size 0.7112 0.8128)
			(layers "F.Cu" "F.Mask" "F.Paste")
			(net "P1V05_STB_NODE1_XDP_B")
		)
	)
	(footprint ""
		(layer "F.Cu")
		(at 81.398364 -17.679416 90)
		(property "Reference" "C148"
			(at -4.546854 5.52323 90)
			(unlocked yes)
			(layer "F.SilkS")
			(effects
				(font
					(size 0.7874 0.5842)
					(thickness 0.1524)
				)
				(justify left)
			)
		)
		(property "Value" ""
			(at 0 0 90)
			(layer "F.Fab")
			(effects
				(font
					(size 1.27 1.27)
				)
			)
		)
		(duplicate_pad_numbers_are_jumpers no)
		(fp_line
			(start 0.7874 -0.4064)
			(end 0.7874 0.4064)
			(stroke
				(width 0.1524)
				(type default)
			)
			(layer "F.SilkS")
		)
		(fp_line
			(start -0.7874 -0.4064)
			(end 0.7874 -0.4064)
			(stroke
				(width 0.1524)
				(type default)
			)
			(layer "F.SilkS")
		)
		(fp_line
			(start 0 0.381)
			(end 0 -0.381)
			(stroke
				(width 0.1524)
				(type default)
			)
			(layer "F.SilkS")
		)
		(fp_line
			(start 0.7874 0.4064)
			(end -0.7874 0.4064)
			(stroke
				(width 0.1524)
				(type default)
			)
			(layer "F.SilkS")
		)
		(fp_line
			(start -0.7874 0.4064)
			(end -0.7874 -0.4064)
			(stroke
				(width 0.1524)
				(type default)
			)
			(layer "F.SilkS")
		)
		(fp_poly
			(pts
				(xy -0.5334 0.254) (xy -0.635 0.254) (xy -0.635 0.2286) (xy -0.635 -0.254) (xy -0.5334 -0.254) (xy -0.5334 -0.2794)
				(xy 0.5334 -0.2794) (xy 0.5334 -0.254) (xy 0.635 -0.254) (xy 0.635 0.254) (xy 0.5334 0.254) (xy 0.5334 0.2794)
				(xy -0.508 0.2794) (xy -0.5334 0.2794)
			)
			(stroke
				(width 0)
				(type default)
			)
			(fill no)
			(layer "F.CrtYd")
		)
		(pad "1" smd rect
			(at 0.40005 0 90)
			(size 0.4572 0.508)
			(layers "F.Cu" "F.Mask" "F.Paste")
			(net "PV_VDDR_NODE1")
		)
		(pad "2" smd rect
			(at -0.40005 0 90)
			(size 0.4572 0.508)
			(layers "F.Cu" "F.Mask" "F.Paste")
			(net "GND")
		)
	)
	(footprint ""
		(layer "F.Cu")
		(at 106.170476 -171.990512)
		(property "Reference" "R762"
			(at 1.206754 0.213614 0)
			(unlocked yes)
			(layer "F.SilkS")
			(effects
				(font
					(size 0.7874 0.5842)
					(thickness 0.1524)
				)
				(justify left)
			)
		)
		(property "Value" ""
			(at 0 0 0)
			(layer "F.Fab")
			(effects
				(font
					(size 1.27 1.27)
				)
			)
		)
		(duplicate_pad_numbers_are_jumpers no)
		(fp_line
			(start -0.7874 -0.4064)
			(end 0.7874 -0.4064)
			(stroke
				(width 0.1524)
				(type default)
			)
			(layer "F.SilkS")
		)
		(fp_line
			(start -0.7874 0.4064)
			(end -0.7874 -0.4064)
			(stroke
				(width 0.1524)
				(type default)
			)
			(layer "F.SilkS")
		)
		(fp_line
			(start 0.7874 -0.4064)
			(end 0.7874 0.4064)
			(stroke
				(width 0.1524)
				(type default)
			)
			(layer "F.SilkS")
		)
		(fp_line
			(start 0.7874 0.4064)
			(end -0.7874 0.4064)
			(stroke
				(width 0.1524)
				(type default)
			)
			(layer "F.SilkS")
		)
		(fp_poly
			(pts
				(xy -0.508 0.2794) (xy -0.508 0.2286) (xy -0.635 0.2286) (xy -0.635 -0.254) (xy -0.5334 -0.254)
				(xy -0.5334 -0.2794) (xy 0.5334 -0.2794) (xy 0.5334 -0.254) (xy 0.635 -0.254) (xy 0.635 0.254) (xy 0.5334 0.254)
				(xy 0.5334 0.2794)
			)
			(stroke
				(width 0)
				(type default)
			)
			(fill no)
			(layer "F.CrtYd")
		)
		(pad "1" smd rect
			(at 0.40005 0)
			(size 0.4572 0.508)
			(layers "F.Cu" "F.Mask" "F.Paste")
			(net "P3V3_NODE1")
		)
		(pad "2" smd rect
			(at -0.40005 0)
			(size 0.4572 0.508)
			(layers "F.Cu" "F.Mask" "F.Paste")
			(net "FNACTRL1_ADD")
		)
	)
)
